(kicad_pcb
	(version 20260206)
	(generator "pcbnew")
	(generator_version "10.0")
	(general
		(thickness 1.6)
		(legacy_teardrops no)
	)
	(paper "A4")
	(title_block
		(title "04192023_DAF0TMB3IC0_F0TG_MB_C_brd_V02_OCP.brd")
		(comment 1 "Grand Teton / footprints 7533-7539 of 8354")
	)
	(layers
		(0 "F.Cu" signal "TOP")
		(4 "In1.Cu" signal "GND")
		(6 "In2.Cu" signal "IN1")
		(8 "In3.Cu" signal "GND1")
		(10 "In4.Cu" signal "IN2")
		(12 "In5.Cu" signal "GND2")
		(14 "In6.Cu" signal "IN3")
		(16 "In7.Cu" signal "GND3")
		(18 "In8.Cu" signal "VCC")
		(20 "In9.Cu" signal "VCC1")
		(22 "In10.Cu" signal "GND4")
		(24 "In11.Cu" signal "IN4")
		(26 "In12.Cu" signal "GND5")
		(28 "In13.Cu" signal "IN5")
		(30 "In14.Cu" signal "GND6")
		(32 "In15.Cu" signal "IN6")
		(34 "In16.Cu" signal "GND7")
		(2 "B.Cu" signal "BOTTOM")
		(9 "F.Adhes" user "F.Adhesive")
		(11 "B.Adhes" user "B.Adhesive")
		(13 "F.Paste" user "Package Geometry/Pastemask Top")
		(15 "B.Paste" user "Package Geometry/Pastemask Bottom")
		(5 "F.SilkS" user "Ref Des/Silkscreen Top")
		(7 "B.SilkS" user "Ref Des/Silkscreen Bottom")
		(1 "F.Mask" user "Board Geometry/Soldermask Top")
		(3 "B.Mask" user "Board Geometry/Soldermask Bottom")
		(17 "Dwgs.User" user "User.Drawings")
		(19 "Cmts.User" user "User.Comments")
		(21 "Eco1.User" user "User.Eco1")
		(23 "Eco2.User" user "User.Eco2")
		(25 "Edge.Cuts" user "Board Geometry/Outline")
		(27 "Margin" user)
		(31 "F.CrtYd" user "Package Geometry/Place Bound Top")
		(29 "B.CrtYd" user "Package Geometry/Place Bound Bottom")
		(35 "F.Fab" user "Ref Des/Assembly Top")
		(33 "B.Fab" user "Ref Des/Assembly Bottom")
	)
	(footprint ""
		(layer "B.Cu")
		(at 174.202852 -8.05688 -90)
		(property "Reference" "R2425"
			(at 0 0 90)
			(layer "B.SilkS")
			(hide yes)
			(effects
				(font
					(size 1.27 1.27)
				)
				(justify mirror)
			)
		)
		(property "Value" ""
			(at 0 0 90)
			(layer "B.Fab")
			(effects
				(font
					(size 1.27 1.27)
				)
				(justify mirror)
			)
		)
		(duplicate_pad_numbers_are_jumpers no)
		(fp_line
			(start -0.7874 0.4064)
			(end 0.7874 0.4064)
			(stroke
				(width 0.1524)
				(type default)
			)
			(layer "B.SilkS")
		)
		(fp_line
			(start 0.7874 0.4064)
			(end 0.7874 -0.4064)
			(stroke
				(width 0.1524)
				(type default)
			)
			(layer "B.SilkS")
		)
		(fp_line
			(start -0.7874 -0.4064)
			(end -0.7874 0.4064)
			(stroke
				(width 0.1524)
				(type default)
			)
			(layer "B.SilkS")
		)
		(fp_line
			(start 0.7874 -0.4064)
			(end -0.7874 -0.4064)
			(stroke
				(width 0.1524)
				(type default)
			)
			(layer "B.SilkS")
		)
		(fp_line
			(start -0.67945 0.3048)
			(end -0.120396 0.3048)
			(stroke
				(width 0.1)
				(type default)
			)
			(layer "B.Fab")
		)
		(fp_line
			(start -0.120396 0.3048)
			(end -0.120396 0.2794)
			(stroke
				(width 0.1)
				(type default)
			)
			(layer "B.Fab")
		)
		(fp_line
			(start 0.12065 0.3048)
			(end 0.67945 0.3048)
			(stroke
				(width 0.1)
				(type default)
			)
			(layer "B.Fab")
		)
		(fp_line
			(start 0.67945 0.3048)
			(end 0.67945 -0.305054)
			(stroke
				(width 0.1)
				(type default)
			)
			(layer "B.Fab")
		)
		(fp_line
			(start -0.120396 0.2794)
			(end 0.12065 0.2794)
			(stroke
				(width 0.1)
				(type default)
			)
			(layer "B.Fab")
		)
		(fp_line
			(start 0.12065 0.2794)
			(end 0.12065 0.3048)
			(stroke
				(width 0.1)
				(type default)
			)
			(layer "B.Fab")
		)
		(fp_line
			(start -0.12065 -0.2794)
			(end -0.12065 -0.3048)
			(stroke
				(width 0.1)
				(type default)
			)
			(layer "B.Fab")
		)
		(fp_line
			(start 0.12065 -0.2794)
			(end -0.12065 -0.2794)
			(stroke
				(width 0.1)
				(type default)
			)
			(layer "B.Fab")
		)
		(fp_line
			(start -0.67945 -0.3048)
			(end -0.67945 0.3048)
			(stroke
				(width 0.1)
				(type default)
			)
			(layer "B.Fab")
		)
		(fp_line
			(start -0.12065 -0.3048)
			(end -0.67945 -0.3048)
			(stroke
				(width 0.1)
				(type default)
			)
			(layer "B.Fab")
		)
		(fp_line
			(start 0.12065 -0.305054)
			(end 0.12065 -0.2794)
			(stroke
				(width 0.1)
				(type default)
			)
			(layer "B.Fab")
		)
		(fp_line
			(start 0.67945 -0.305054)
			(end 0.12065 -0.305054)
			(stroke
				(width 0.1)
				(type default)
			)
			(layer "B.Fab")
		)
		(pad "1" smd circle
			(at 0.40005 0 90)
			(size 0 0)
			(layers "B.Cu" "B.Mask" "B.Paste")
			(net "SMB_OCP_V3_2_3V3AUX_SCL")
		)
		(pad "2" smd circle
			(at -0.40005 0 90)
			(size 0 0)
			(layers "B.Cu" "B.Mask" "B.Paste")
			(net "SMB_OCP_V3_2_3V3AUX_SCL_R0")
		)
	)
	(footprint ""
		(layer "B.Cu")
		(at 120.856248 -165.079934 -90)
		(property "Reference" "PC332_2"
			(at 0 0 90)
			(layer "B.SilkS")
			(hide yes)
			(effects
				(font
					(size 1.27 1.27)
				)
				(justify mirror)
			)
		)
		(property "Value" ""
			(at 0 0 90)
			(layer "B.Fab")
			(effects
				(font
					(size 1.27 1.27)
				)
				(justify mirror)
			)
		)
		(duplicate_pad_numbers_are_jumpers no)
		(fp_line
			(start -1.524 0.762)
			(end 1.524 0.762)
			(stroke
				(width 0.1524)
				(type default)
			)
			(layer "B.SilkS")
		)
		(fp_line
			(start 1.524 0.762)
			(end 1.524 -0.762)
			(stroke
				(width 0.1524)
				(type default)
			)
			(layer "B.SilkS")
		)
		(fp_line
			(start -1.524 -0.762)
			(end -1.524 0.762)
			(stroke
				(width 0.1524)
				(type default)
			)
			(layer "B.SilkS")
		)
		(fp_line
			(start 1.524 -0.762)
			(end -1.524 -0.762)
			(stroke
				(width 0.1524)
				(type default)
			)
			(layer "B.SilkS")
		)
		(fp_line
			(start -1.1049 0.724916)
			(end -1.1049 -0.724916)
			(stroke
				(width 0.1)
				(type default)
			)
			(layer "B.Fab")
		)
		(fp_line
			(start 1.1049 0.724916)
			(end -1.1049 0.724916)
			(stroke
				(width 0.1)
				(type default)
			)
			(layer "B.Fab")
		)
		(fp_line
			(start -1.1049 -0.724916)
			(end 1.1049 -0.724916)
			(stroke
				(width 0.1)
				(type default)
			)
			(layer "B.Fab")
		)
		(fp_line
			(start 1.1049 -0.724916)
			(end 1.1049 0.724916)
			(stroke
				(width 0.1)
				(type default)
			)
			(layer "B.Fab")
		)
		(pad "1" smd rect
			(at 0.889 0 270)
			(size 1.016 1.27)
			(layers "B.Cu" "B.Mask" "B.Paste")
			(net "SW_P12V_AUX_PVDDCR_SOC_P1_FLT")
		)
		(pad "2" smd rect
			(at -0.889 0 270)
			(size 1.016 1.27)
			(layers "B.Cu" "B.Mask" "B.Paste")
			(net "GND")
		)
	)
	(footprint ""
		(layer "B.Cu")
		(at 387.41858 -396.393162 -90)
		(property "Reference" "C1010"
			(at 0 0 90)
			(layer "B.SilkS")
			(hide yes)
			(effects
				(font
					(size 1.27 1.27)
				)
				(justify mirror)
			)
		)
		(property "Value" ""
			(at 0 0 90)
			(layer "B.Fab")
			(effects
				(font
					(size 1.27 1.27)
				)
				(justify mirror)
			)
		)
		(duplicate_pad_numbers_are_jumpers no)
		(fp_line
			(start -0.299974 0.150114)
			(end 0.299974 0.150114)
			(stroke
				(width 0.1)
				(type default)
			)
			(layer "B.Fab")
		)
		(fp_line
			(start 0.299974 0.150114)
			(end 0.299974 -0.150114)
			(stroke
				(width 0.1)
				(type default)
			)
			(layer "B.Fab")
		)
		(fp_line
			(start -0.299974 -0.150114)
			(end -0.299974 0.150114)
			(stroke
				(width 0.1)
				(type default)
			)
			(layer "B.Fab")
		)
		(fp_line
			(start 0.299974 -0.150114)
			(end -0.299974 -0.150114)
			(stroke
				(width 0.1)
				(type default)
			)
			(layer "B.Fab")
		)
		(pad "1" smd rect
			(at 0.2667 0 90)
			(size 0.3048 0.381)
			(layers "B.Cu" "B.Mask" "B.Paste")
			(net "P0V9_CPU0_RT3_2A")
		)
		(pad "2" smd rect
			(at -0.2667 0 90)
			(size 0.3048 0.381)
			(layers "B.Cu" "B.Mask" "B.Paste")
			(net "GND")
		)
	)
	(footprint ""
		(layer "B.Cu")
		(at 154.346148 -388.011162 -90)
		(property "Reference" "C374"
			(at 0 0 90)
			(layer "B.SilkS")
			(hide yes)
			(effects
				(font
					(size 1.27 1.27)
				)
				(justify mirror)
			)
		)
		(property "Value" ""
			(at 0 0 90)
			(layer "B.Fab")
			(effects
				(font
					(size 1.27 1.27)
				)
				(justify mirror)
			)
		)
		(duplicate_pad_numbers_are_jumpers no)
		(fp_line
			(start -0.299974 0.150114)
			(end 0.299974 0.150114)
			(stroke
				(width 0.1)
				(type default)
			)
			(layer "B.Fab")
		)
		(fp_line
			(start 0.299974 0.150114)
			(end 0.299974 -0.150114)
			(stroke
				(width 0.1)
				(type default)
			)
			(layer "B.Fab")
		)
		(fp_line
			(start -0.299974 -0.150114)
			(end -0.299974 0.150114)
			(stroke
				(width 0.1)
				(type default)
			)
			(layer "B.Fab")
		)
		(fp_line
			(start 0.299974 -0.150114)
			(end -0.299974 -0.150114)
			(stroke
				(width 0.1)
				(type default)
			)
			(layer "B.Fab")
		)
		(pad "1" smd rect
			(at 0.2667 0 90)
			(size 0.3048 0.381)
			(layers "B.Cu" "B.Mask" "B.Paste")
			(net "P1V8_CPU1_RT2_1A")
		)
		(pad "2" smd rect
			(at -0.2667 0 90)
			(size 0.3048 0.381)
			(layers "B.Cu" "B.Mask" "B.Paste")
			(net "GND")
		)
	)
	(footprint ""
		(layer "B.Cu")
		(at 176.657 -100.294948 -90)
		(property "Reference" "R188"
			(at 0 0 90)
			(layer "B.SilkS")
			(hide yes)
			(effects
				(font
					(size 1.27 1.27)
				)
				(justify mirror)
			)
		)
		(property "Value" ""
			(at 0 0 90)
			(layer "B.Fab")
			(effects
				(font
					(size 1.27 1.27)
				)
				(justify mirror)
			)
		)
		(duplicate_pad_numbers_are_jumpers no)
		(fp_line
			(start -0.7874 0.4064)
			(end 0.7874 0.4064)
			(stroke
				(width 0.1524)
				(type default)
			)
			(layer "B.SilkS")
		)
		(fp_line
			(start 0.7874 0.4064)
			(end 0.7874 -0.4064)
			(stroke
				(width 0.1524)
				(type default)
			)
			(layer "B.SilkS")
		)
		(fp_line
			(start -0.7874 -0.4064)
			(end -0.7874 0.4064)
			(stroke
				(width 0.1524)
				(type default)
			)
			(layer "B.SilkS")
		)
		(fp_line
			(start 0.7874 -0.4064)
			(end -0.7874 -0.4064)
			(stroke
				(width 0.1524)
				(type default)
			)
			(layer "B.SilkS")
		)
		(fp_line
			(start -0.67945 0.3048)
			(end -0.120396 0.3048)
			(stroke
				(width 0.1)
				(type default)
			)
			(layer "B.Fab")
		)
		(fp_line
			(start -0.120396 0.3048)
			(end -0.120396 0.2794)
			(stroke
				(width 0.1)
				(type default)
			)
			(layer "B.Fab")
		)
		(fp_line
			(start 0.12065 0.3048)
			(end 0.67945 0.3048)
			(stroke
				(width 0.1)
				(type default)
			)
			(layer "B.Fab")
		)
		(fp_line
			(start 0.67945 0.3048)
			(end 0.67945 -0.305054)
			(stroke
				(width 0.1)
				(type default)
			)
			(layer "B.Fab")
		)
		(fp_line
			(start -0.120396 0.2794)
			(end 0.12065 0.2794)
			(stroke
				(width 0.1)
				(type default)
			)
			(layer "B.Fab")
		)
		(fp_line
			(start 0.12065 0.2794)
			(end 0.12065 0.3048)
			(stroke
				(width 0.1)
				(type default)
			)
			(layer "B.Fab")
		)
		(fp_line
			(start -0.12065 -0.2794)
			(end -0.12065 -0.3048)
			(stroke
				(width 0.1)
				(type default)
			)
			(layer "B.Fab")
		)
		(fp_line
			(start 0.12065 -0.2794)
			(end -0.12065 -0.2794)
			(stroke
				(width 0.1)
				(type default)
			)
			(layer "B.Fab")
		)
		(fp_line
			(start -0.67945 -0.3048)
			(end -0.67945 0.3048)
			(stroke
				(width 0.1)
				(type default)
			)
			(layer "B.Fab")
		)
		(fp_line
			(start -0.12065 -0.3048)
			(end -0.67945 -0.3048)
			(stroke
				(width 0.1)
				(type default)
			)
			(layer "B.Fab")
		)
		(fp_line
			(start 0.12065 -0.305054)
			(end 0.12065 -0.2794)
			(stroke
				(width 0.1)
				(type default)
			)
			(layer "B.Fab")
		)
		(fp_line
			(start 0.67945 -0.305054)
			(end 0.12065 -0.305054)
			(stroke
				(width 0.1)
				(type default)
			)
			(layer "B.Fab")
		)
		(pad "1" smd circle
			(at 0.40005 0 90)
			(size 0 0)
			(layers "B.Cu" "B.Mask" "B.Paste")
			(net "FM_BMC_READY_N")
		)
		(pad "2" smd circle
			(at -0.40005 0 90)
			(size 0 0)
			(layers "B.Cu" "B.Mask" "B.Paste")
			(net "FM_BMC_READY_R_N")
		)
	)
	(footprint ""
		(layer "B.Cu")
		(at 146.115024 -391.340848 -90)
		(property "Reference" "C413"
			(at 0 0 90)
			(layer "B.SilkS")
			(hide yes)
			(effects
				(font
					(size 1.27 1.27)
				)
				(justify mirror)
			)
		)
		(property "Value" ""
			(at 0 0 90)
			(layer "B.Fab")
			(effects
				(font
					(size 1.27 1.27)
				)
				(justify mirror)
			)
		)
		(duplicate_pad_numbers_are_jumpers no)
		(fp_line
			(start -0.7874 0.4064)
			(end 0.7874 0.4064)
			(stroke
				(width 0.1524)
				(type default)
			)
			(layer "B.SilkS")
		)
		(fp_line
			(start 0.7874 0.4064)
			(end 0.7874 -0.4064)
			(stroke
				(width 0.1524)
				(type default)
			)
			(layer "B.SilkS")
		)
		(fp_line
			(start -0.7874 -0.4064)
			(end -0.7874 0.4064)
			(stroke
				(width 0.1524)
				(type default)
			)
			(layer "B.SilkS")
		)
		(fp_line
			(start 0.7874 -0.4064)
			(end -0.7874 -0.4064)
			(stroke
				(width 0.1524)
				(type default)
			)
			(layer "B.SilkS")
		)
		(fp_line
			(start -0.67945 0.3048)
			(end -0.120396 0.3048)
			(stroke
				(width 0.1)
				(type default)
			)
			(layer "B.Fab")
		)
		(fp_line
			(start -0.120396 0.3048)
			(end -0.120396 0.2794)
			(stroke
				(width 0.1)
				(type default)
			)
			(layer "B.Fab")
		)
		(fp_line
			(start 0.12065 0.3048)
			(end 0.67945 0.3048)
			(stroke
				(width 0.1)
				(type default)
			)
			(layer "B.Fab")
		)
		(fp_line
			(start 0.67945 0.3048)
			(end 0.67945 -0.305054)
			(stroke
				(width 0.1)
				(type default)
			)
			(layer "B.Fab")
		)
		(fp_line
			(start -0.120396 0.2794)
			(end 0.12065 0.2794)
			(stroke
				(width 0.1)
				(type default)
			)
			(layer "B.Fab")
		)
		(fp_line
			(start 0.12065 0.2794)
			(end 0.12065 0.3048)
			(stroke
				(width 0.1)
				(type default)
			)
			(layer "B.Fab")
		)
		(fp_line
			(start -0.12065 -0.2794)
			(end -0.12065 -0.3048)
			(stroke
				(width 0.1)
				(type default)
			)
			(layer "B.Fab")
		)
		(fp_line
			(start 0.12065 -0.2794)
			(end -0.12065 -0.2794)
			(stroke
				(width 0.1)
				(type default)
			)
			(layer "B.Fab")
		)
		(fp_line
			(start -0.67945 -0.3048)
			(end -0.67945 0.3048)
			(stroke
				(width 0.1)
				(type default)
			)
			(layer "B.Fab")
		)
		(fp_line
			(start -0.12065 -0.3048)
			(end -0.67945 -0.3048)
			(stroke
				(width 0.1)
				(type default)
			)
			(layer "B.Fab")
		)
		(fp_line
			(start 0.12065 -0.305054)
			(end 0.12065 -0.2794)
			(stroke
				(width 0.1)
				(type default)
			)
			(layer "B.Fab")
		)
		(fp_line
			(start 0.67945 -0.305054)
			(end 0.12065 -0.305054)
			(stroke
				(width 0.1)
				(type default)
			)
			(layer "B.Fab")
		)
		(pad "1" smd circle
			(at 0.40005 0 90)
			(size 0 0)
			(layers "B.Cu" "B.Mask" "B.Paste")
			(net "P0V9_CPU1_RT2_2A")
		)
		(pad "2" smd circle
			(at -0.40005 0 90)
			(size 0 0)
			(layers "B.Cu" "B.Mask" "B.Paste")
			(net "GND")
		)
	)
	(footprint ""
		(layer "B.Cu")
		(at 165.419532 -431.57648 -90)
		(property "Reference" "R4572"
			(at 0 0 90)
			(layer "B.SilkS")
			(hide yes)
			(effects
				(font
					(size 1.27 1.27)
				)
				(justify mirror)
			)
		)
		(property "Value" ""
			(at 0 0 90)
			(layer "B.Fab")
			(effects
				(font
					(size 1.27 1.27)
				)
				(justify mirror)
			)
		)
		(duplicate_pad_numbers_are_jumpers no)
		(fp_line
			(start -0.7874 0.4064)
			(end 0.7874 0.4064)
			(stroke
				(width 0.1524)
				(type default)
			)
			(layer "B.SilkS")
		)
		(fp_line
			(start 0.7874 0.4064)
			(end 0.7874 -0.4064)
			(stroke
				(width 0.1524)
				(type default)
			)
			(layer "B.SilkS")
		)
		(fp_line
			(start -0.7874 -0.4064)
			(end -0.7874 0.4064)
			(stroke
				(width 0.1524)
				(type default)
			)
			(layer "B.SilkS")
		)
		(fp_line
			(start 0.7874 -0.4064)
			(end -0.7874 -0.4064)
			(stroke
				(width 0.1524)
				(type default)
			)
			(layer "B.SilkS")
		)
		(fp_line
			(start -0.67945 0.3048)
			(end -0.120396 0.3048)
			(stroke
				(width 0.1)
				(type default)
			)
			(layer "B.Fab")
		)
		(fp_line
			(start -0.120396 0.3048)
			(end -0.120396 0.2794)
			(stroke
				(width 0.1)
				(type default)
			)
			(layer "B.Fab")
		)
		(fp_line
			(start 0.12065 0.3048)
			(end 0.67945 0.3048)
			(stroke
				(width 0.1)
				(type default)
			)
			(layer "B.Fab")
		)
		(fp_line
			(start 0.67945 0.3048)
			(end 0.67945 -0.305054)
			(stroke
				(width 0.1)
				(type default)
			)
			(layer "B.Fab")
		)
		(fp_line
			(start -0.120396 0.2794)
			(end 0.12065 0.2794)
			(stroke
				(width 0.1)
				(type default)
			)
			(layer "B.Fab")
		)
		(fp_line
			(start 0.12065 0.2794)
			(end 0.12065 0.3048)
			(stroke
				(width 0.1)
				(type default)
			)
			(layer "B.Fab")
		)
		(fp_line
			(start -0.12065 -0.2794)
			(end -0.12065 -0.3048)
			(stroke
				(width 0.1)
				(type default)
			)
			(layer "B.Fab")
		)
		(fp_line
			(start 0.12065 -0.2794)
			(end -0.12065 -0.2794)
			(stroke
				(width 0.1)
				(type default)
			)
			(layer "B.Fab")
		)
		(fp_line
			(start -0.67945 -0.3048)
			(end -0.67945 0.3048)
			(stroke
				(width 0.1)
				(type default)
			)
			(layer "B.Fab")
		)
		(fp_line
			(start -0.12065 -0.3048)
			(end -0.67945 -0.3048)
			(stroke
				(width 0.1)
				(type default)
			)
			(layer "B.Fab")
		)
		(fp_line
			(start 0.12065 -0.305054)
			(end 0.12065 -0.2794)
			(stroke
				(width 0.1)
				(type default)
			)
			(layer "B.Fab")
		)
		(fp_line
			(start 0.67945 -0.305054)
			(end 0.12065 -0.305054)
			(stroke
				(width 0.1)
				(type default)
			)
			(layer "B.Fab")
		)
		(pad "1" smd circle
			(at 0.40005 0 90)
			(size 0 0)
			(layers "B.Cu" "B.Mask" "B.Paste")
			(net "GPU_3V3IO_RSVD1_FFU")
		)
		(pad "2" smd circle
			(at -0.40005 0 90)
			(size 0 0)
			(layers "B.Cu" "B.Mask" "B.Paste")
			(net "GPU_3V3IO_RSVD1_FFU_ISO")
		)
	)
)
